# Bryce Canyon_Rear_Drive_Plane_Board_Stackup.xlsx — Storage_PCB_Test_Note (pcb-stackup)
| 編號(Number) | 內容(Item) | 附加檔案(Files) | 附加說明(Description) |
| 1 | Impedance traceability and test |  | 1、板廠在HVM量產階段採用AQL 0.65 正常檢驗水準二級來抽樣，利用Excel範本(PCB_Vendor_PCB_Number(XXXXX-SA)_Impedance_Report_Template_Date.xlsx)在量產階段(HVM 90天後)，不同lot 的量測結果分開於不同的分頁中，記錄其Min, Max, Mean, Median, Sigma, CP, CK, CPK等數值。 2、阻抗CPK的允收條件為 c= 0 (HVM 90天後)；阻抗數值的允收條件為 ±10%(EVT, DVT, PVT,HVM)。 3、阻抗測試條需擺放於折斷邊上。 |
| 2 | Delta-L coupon test |  | 1、板廠在HVM量產階段每個lot隨機挑選5 pcs且最大總數量為 30 pcs，利用Excel範本(PCB_Vendor_PCB_Number(XXXXX-SA)_Delta-L_Report_Template_Date.xlsx)中的格式及步驟. 2、Delta-L測試條的設計為85 ohm走線，需涵蓋的層面為85 ohm與100 ohm的所有走線層面。 3、損耗的允收條件為為 c= 0 (HVM 90天後)；小於疊構中敘述的dB/inch數值(EVT, DVT, PVT, HVM)。 |
